# T6G (Grand Teton) — schematic netlist excerpt (pin names and nets, part order shuffled) for the footprints in the layout excerpt that follows; sources: Cadence DE-HDL packaged netlist, KiCad conversion of 04192023_DAF0TMB3IC0_F0TG_MB_C_brd_V02_OCP.brd

PR6622  Q_RES  8.87K 1% EMPTY  pkg 0402LF  page 365 : A = P0V9_RETIMER_CPU1_LSET1 ; B = GND
PC2089  Q_CAP  6800PF 50V 10% X7R  pkg C0402  page 134 : A = P3V3_OCP_GATE_PU202_1 ; B = GND

(kicad_pcb
	(version 20260206)
	(generator "pcbnew")
	(generator_version "10.0")
	(general
		(thickness 1.6)
		(legacy_teardrops no)
	)
	(paper "A4")
	(title_block
		(title "04192023_DAF0TMB3IC0_F0TG_MB_C_brd_V02_OCP.brd")
		(comment 1 "Grand Teton / footprints 1672-1673 of 8354")
	)
	(layers
		(0 "F.Cu" signal "TOP")
		(4 "In1.Cu" signal "GND")
		(6 "In2.Cu" signal "IN1")
		(8 "In3.Cu" signal "GND1")
		(10 "In4.Cu" signal "IN2")
		(12 "In5.Cu" signal "GND2")
		(14 "In6.Cu" signal "IN3")
		(16 "In7.Cu" signal "GND3")
		(18 "In8.Cu" signal "VCC")
		(20 "In9.Cu" signal "VCC1")
		(22 "In10.Cu" signal "GND4")
		(24 "In11.Cu" signal "IN4")
		(26 "In12.Cu" signal "GND5")
		(28 "In13.Cu" signal "IN5")
		(30 "In14.Cu" signal "GND6")
		(32 "In15.Cu" signal "IN6")
		(34 "In16.Cu" signal "GND7")
		(2 "B.Cu" signal "BOTTOM")
		(9 "F.Adhes" user "F.Adhesive")
		(11 "B.Adhes" user "B.Adhesive")
		(13 "F.Paste" user "Package Geometry/Pastemask Top")
		(15 "B.Paste" user "Package Geometry/Pastemask Bottom")
		(5 "F.SilkS" user "Ref Des/Silkscreen Top")
		(7 "B.SilkS" user "Ref Des/Silkscreen Bottom")
		(1 "F.Mask" user "Board Geometry/Soldermask Top")
		(3 "B.Mask" user "Board Geometry/Soldermask Bottom")
		(17 "Dwgs.User" user "User.Drawings")
		(19 "Cmts.User" user "User.Comments")
		(21 "Eco1.User" user "User.Eco1")
		(23 "Eco2.User" user "User.Eco2")
		(25 "Edge.Cuts" user "Board Geometry/Outline")
		(27 "Margin" user)
		(31 "F.CrtYd" user "Package Geometry/Place Bound Top")
		(29 "B.CrtYd" user "Package Geometry/Place Bound Bottom")
		(35 "F.Fab" user "Ref Des/Assembly Top")
		(33 "B.Fab" user "Ref Des/Assembly Bottom")
	)
	(footprint ""
		(layer "F.Cu")
		(at 16.051784 -394.428726)
		(property "Reference" "PR6622"
			(at 0 0 0)
			(layer "F.SilkS")
			(hide yes)
			(effects
				(font
					(size 1.27 1.27)
				)
			)
		)
		(property "Value" ""
			(at 0 0 0)
			(layer "F.Fab")
			(effects
				(font
					(size 1.27 1.27)
				)
			)
		)
		(duplicate_pad_numbers_are_jumpers no)
		(fp_line
			(start -0.7874 -0.4064)
			(end 0.7874 -0.4064)
			(stroke
				(width 0.1524)
				(type default)
			)
			(layer "F.SilkS")
		)
		(fp_line
			(start -0.7874 0.4064)
			(end -0.7874 -0.4064)
			(stroke
				(width 0.1524)
				(type default)
			)
			(layer "F.SilkS")
		)
		(fp_line
			(start 0.7874 -0.4064)
			(end 0.7874 0.4064)
			(stroke
				(width 0.1524)
				(type default)
			)
			(layer "F.SilkS")
		)
		(fp_line
			(start 0.7874 0.4064)
			(end -0.7874 0.4064)
			(stroke
				(width 0.1524)
				(type default)
			)
			(layer "F.SilkS")
		)
		(fp_line
			(start -0.67945 -0.305054)
			(end -0.12065 -0.305054)
			(stroke
				(width 0.1)
				(type default)
			)
			(layer "F.Fab")
		)
		(fp_line
			(start -0.67945 0.3048)
			(end -0.67945 -0.305054)
			(stroke
				(width 0.1)
				(type default)
			)
			(layer "F.Fab")
		)
		(fp_line
			(start -0.12065 -0.305054)
			(end -0.12065 -0.2794)
			(stroke
				(width 0.1)
				(type default)
			)
			(layer "F.Fab")
		)
		(fp_line
			(start -0.12065 -0.2794)
			(end 0.12065 -0.2794)
			(stroke
				(width 0.1)
				(type default)
			)
			(layer "F.Fab")
		)
		(fp_line
			(start -0.12065 0.2794)
			(end -0.12065 0.3048)
			(stroke
				(width 0.1)
				(type default)
			)
			(layer "F.Fab")
		)
		(fp_line
			(start -0.12065 0.3048)
			(end -0.67945 0.3048)
			(stroke
				(width 0.1)
				(type default)
			)
			(layer "F.Fab")
		)
		(fp_line
			(start 0.120396 0.2794)
			(end -0.12065 0.2794)
			(stroke
				(width 0.1)
				(type default)
			)
			(layer "F.Fab")
		)
		(fp_line
			(start 0.120396 0.3048)
			(end 0.120396 0.2794)
			(stroke
				(width 0.1)
				(type default)
			)
			(layer "F.Fab")
		)
		(fp_line
			(start 0.12065 -0.3048)
			(end 0.67945 -0.3048)
			(stroke
				(width 0.1)
				(type default)
			)
			(layer "F.Fab")
		)
		(fp_line
			(start 0.12065 -0.2794)
			(end 0.12065 -0.3048)
			(stroke
				(width 0.1)
				(type default)
			)
			(layer "F.Fab")
		)
		(fp_line
			(start 0.67945 -0.3048)
			(end 0.67945 0.3048)
			(stroke
				(width 0.1)
				(type default)
			)
			(layer "F.Fab")
		)
		(fp_line
			(start 0.67945 0.3048)
			(end 0.120396 0.3048)
			(stroke
				(width 0.1)
				(type default)
			)
			(layer "F.Fab")
		)
		(pad "1" smd circle
			(at -0.40005 0)
			(size 0 0)
			(layers "F.Cu" "F.Mask" "F.Paste")
			(net "P0V9_RETIMER_CPU1_LSET1")
		)
		(pad "2" smd circle
			(at 0.40005 0)
			(size 0 0)
			(layers "F.Cu" "F.Mask" "F.Paste")
			(net "GND")
		)
	)
	(footprint ""
		(layer "F.Cu")
		(at 434.448204 -103.927402 -90)
		(property "Reference" "PC2089"
			(at 0 0 270)
			(layer "F.SilkS")
			(hide yes)
			(effects
				(font
					(size 1.27 1.27)
				)
			)
		)
		(property "Value" ""
			(at 0 0 270)
			(layer "F.Fab")
			(effects
				(font
					(size 1.27 1.27)
				)
			)
		)
		(duplicate_pad_numbers_are_jumpers no)
		(fp_line
			(start -0.7874 0.4064)
			(end -0.7874 -0.4064)
			(stroke
				(width 0.1524)
				(type default)
			)
			(layer "F.SilkS")
		)
		(fp_line
			(start 0.7874 0.4064)
			(end -0.7874 0.4064)
			(stroke
				(width 0.1524)
				(type default)
			)
			(layer "F.SilkS")
		)
		(fp_line
			(start -0.7874 -0.4064)
			(end 0.7874 -0.4064)
			(stroke
				(width 0.1524)
				(type default)
			)
			(layer "F.SilkS")
		)
		(fp_line
			(start 0.7874 -0.4064)
			(end 0.7874 0.4064)
			(stroke
				(width 0.1524)
				(type default)
			)
			(layer "F.SilkS")
		)
		(fp_line
			(start -0.67945 0.3048)
			(end -0.67945 -0.305054)
			(stroke
				(width 0.1)
				(type default)
			)
			(layer "F.Fab")
		)
		(fp_line
			(start -0.12065 0.3048)
			(end -0.67945 0.3048)
			(stroke
				(width 0.1)
				(type default)
			)
			(layer "F.Fab")
		)
		(fp_line
			(start 0.120396 0.3048)
			(end 0.120396 0.2794)
			(stroke
				(width 0.1)
				(type default)
			)
			(layer "F.Fab")
		)
		(fp_line
			(start 0.67945 0.3048)
			(end 0.120396 0.3048)
			(stroke
				(width 0.1)
				(type default)
			)
			(layer "F.Fab")
		)
		(fp_line
			(start -0.12065 0.2794)
			(end -0.12065 0.3048)
			(stroke
				(width 0.1)
				(type default)
			)
			(layer "F.Fab")
		)
		(fp_line
			(start 0.120396 0.2794)
			(end -0.12065 0.2794)
			(stroke
				(width 0.1)
				(type default)
			)
			(layer "F.Fab")
		)
		(fp_line
			(start -0.12065 -0.2794)
			(end 0.12065 -0.2794)
			(stroke
				(width 0.1)
				(type default)
			)
			(layer "F.Fab")
		)
		(fp_line
			(start 0.12065 -0.2794)
			(end 0.12065 -0.3048)
			(stroke
				(width 0.1)
				(type default)
			)
			(layer "F.Fab")
		)
		(fp_line
			(start 0.12065 -0.3048)
			(end 0.67945 -0.3048)
			(stroke
				(width 0.1)
				(type default)
			)
			(layer "F.Fab")
		)
		(fp_line
			(start 0.67945 -0.3048)
			(end 0.67945 0.3048)
			(stroke
				(width 0.1)
				(type default)
			)
			(layer "F.Fab")
		)
		(fp_line
			(start -0.67945 -0.305054)
			(end -0.12065 -0.305054)
			(stroke
				(width 0.1)
				(type default)
			)
			(layer "F.Fab")
		)
		(fp_line
			(start -0.12065 -0.305054)
			(end -0.12065 -0.2794)
			(stroke
				(width 0.1)
				(type default)
			)
			(layer "F.Fab")
		)
		(pad "1" smd circle
			(at -0.40005 0 270)
			(size 0 0)
			(layers "F.Cu" "F.Mask" "F.Paste")
			(net "P3V3_OCP_GATE_PU202_1")
		)
		(pad "2" smd circle
			(at 0.40005 0 270)
			(size 0 0)
			(layers "F.Cu" "F.Mask" "F.Paste")
			(net "GND")
		)
	)
)
